(kicad_pcb
	(version 20260206)
	(generator "pcbnew")
	(generator_version "10.0")
	(general
		(thickness 1.6)
		(legacy_teardrops no)
	)
	(paper "A4")
	(title_block
		(title "04192023_DAF0TMB3IC0_F0TG_MB_C_brd_V02_OCP.brd")
		(comment 1 "Grand Teton / footprints 207-215 of 8354")
	)
	(layers
		(0 "F.Cu" signal "TOP")
		(4 "In1.Cu" signal "GND")
		(6 "In2.Cu" signal "IN1")
		(8 "In3.Cu" signal "GND1")
		(10 "In4.Cu" signal "IN2")
		(12 "In5.Cu" signal "GND2")
		(14 "In6.Cu" signal "IN3")
		(16 "In7.Cu" signal "GND3")
		(18 "In8.Cu" signal "VCC")
		(20 "In9.Cu" signal "VCC1")
		(22 "In10.Cu" signal "GND4")
		(24 "In11.Cu" signal "IN4")
		(26 "In12.Cu" signal "GND5")
		(28 "In13.Cu" signal "IN5")
		(30 "In14.Cu" signal "GND6")
		(32 "In15.Cu" signal "IN6")
		(34 "In16.Cu" signal "GND7")
		(2 "B.Cu" signal "BOTTOM")
		(9 "F.Adhes" user "F.Adhesive")
		(11 "B.Adhes" user "B.Adhesive")
		(13 "F.Paste" user "Package Geometry/Pastemask Top")
		(15 "B.Paste" user "Package Geometry/Pastemask Bottom")
		(5 "F.SilkS" user "Ref Des/Silkscreen Top")
		(7 "B.SilkS" user "Ref Des/Silkscreen Bottom")
		(1 "F.Mask" user "Board Geometry/Soldermask Top")
		(3 "B.Mask" user "Board Geometry/Soldermask Bottom")
		(17 "Dwgs.User" user "User.Drawings")
		(19 "Cmts.User" user "User.Comments")
		(21 "Eco1.User" user "User.Eco1")
		(23 "Eco2.User" user "User.Eco2")
		(25 "Edge.Cuts" user "Board Geometry/Outline")
		(27 "Margin" user)
		(31 "F.CrtYd" user "Package Geometry/Place Bound Top")
		(29 "B.CrtYd" user "Package Geometry/Place Bound Bottom")
		(35 "F.Fab" user "Ref Des/Assembly Top")
		(33 "B.Fab" user "Ref Des/Assembly Bottom")
	)
	(footprint ""
		(layer "F.Cu")
		(at 398.61744 -381.41783 -90)
		(property "Reference" "C865"
			(at 0 0 270)
			(layer "F.SilkS")
			(hide yes)
			(effects
				(font
					(size 1.27 1.27)
				)
			)
		)
		(property "Value" ""
			(at 0 0 270)
			(layer "F.Fab")
			(effects
				(font
					(size 1.27 1.27)
				)
			)
		)
		(duplicate_pad_numbers_are_jumpers no)
		(fp_line
			(start -0.299974 0.150114)
			(end -0.299974 -0.150114)
			(stroke
				(width 0.1)
				(type default)
			)
			(layer "F.Fab")
		)
		(fp_line
			(start 0.299974 0.150114)
			(end -0.299974 0.150114)
			(stroke
				(width 0.1)
				(type default)
			)
			(layer "F.Fab")
		)
		(fp_line
			(start -0.299974 -0.150114)
			(end 0.299974 -0.150114)
			(stroke
				(width 0.1)
				(type default)
			)
			(layer "F.Fab")
		)
		(fp_line
			(start 0.299974 -0.150114)
			(end 0.299974 0.150114)
			(stroke
				(width 0.1)
				(type default)
			)
			(layer "F.Fab")
		)
		(pad "1" smd rect
			(at -0.2667 0 270)
			(size 0.3048 0.381)
			(layers "F.Cu" "F.Mask" "F.Paste")
			(net "P5E_CPU0_P2_TX_C_DP<2>")
		)
		(pad "2" smd rect
			(at 0.2667 0 270)
			(size 0.3048 0.381)
			(layers "F.Cu" "F.Mask" "F.Paste")
			(net "P5E_CPU0_P2_TX_DP<2>")
		)
	)
	(footprint ""
		(layer "F.Cu")
		(at 87.557864 -57.16778)
		(property "Reference" "R3833"
			(at 0 0 0)
			(layer "F.SilkS")
			(hide yes)
			(effects
				(font
					(size 1.27 1.27)
				)
			)
		)
		(property "Value" ""
			(at 0 0 0)
			(layer "F.Fab")
			(effects
				(font
					(size 1.27 1.27)
				)
			)
		)
		(duplicate_pad_numbers_are_jumpers no)
		(fp_line
			(start -0.7874 -0.4064)
			(end 0.7874 -0.4064)
			(stroke
				(width 0.1524)
				(type default)
			)
			(layer "F.SilkS")
		)
		(fp_line
			(start -0.7874 0.4064)
			(end -0.7874 -0.4064)
			(stroke
				(width 0.1524)
				(type default)
			)
			(layer "F.SilkS")
		)
		(fp_line
			(start 0.7874 -0.4064)
			(end 0.7874 0.4064)
			(stroke
				(width 0.1524)
				(type default)
			)
			(layer "F.SilkS")
		)
		(fp_line
			(start 0.7874 0.4064)
			(end -0.7874 0.4064)
			(stroke
				(width 0.1524)
				(type default)
			)
			(layer "F.SilkS")
		)
		(fp_line
			(start -0.67945 -0.305054)
			(end -0.12065 -0.305054)
			(stroke
				(width 0.1)
				(type default)
			)
			(layer "F.Fab")
		)
		(fp_line
			(start -0.67945 0.3048)
			(end -0.67945 -0.305054)
			(stroke
				(width 0.1)
				(type default)
			)
			(layer "F.Fab")
		)
		(fp_line
			(start -0.12065 -0.305054)
			(end -0.12065 -0.2794)
			(stroke
				(width 0.1)
				(type default)
			)
			(layer "F.Fab")
		)
		(fp_line
			(start -0.12065 -0.2794)
			(end 0.12065 -0.2794)
			(stroke
				(width 0.1)
				(type default)
			)
			(layer "F.Fab")
		)
		(fp_line
			(start -0.12065 0.2794)
			(end -0.12065 0.3048)
			(stroke
				(width 0.1)
				(type default)
			)
			(layer "F.Fab")
		)
		(fp_line
			(start -0.12065 0.3048)
			(end -0.67945 0.3048)
			(stroke
				(width 0.1)
				(type default)
			)
			(layer "F.Fab")
		)
		(fp_line
			(start 0.120396 0.2794)
			(end -0.12065 0.2794)
			(stroke
				(width 0.1)
				(type default)
			)
			(layer "F.Fab")
		)
		(fp_line
			(start 0.120396 0.3048)
			(end 0.120396 0.2794)
			(stroke
				(width 0.1)
				(type default)
			)
			(layer "F.Fab")
		)
		(fp_line
			(start 0.12065 -0.3048)
			(end 0.67945 -0.3048)
			(stroke
				(width 0.1)
				(type default)
			)
			(layer "F.Fab")
		)
		(fp_line
			(start 0.12065 -0.2794)
			(end 0.12065 -0.3048)
			(stroke
				(width 0.1)
				(type default)
			)
			(layer "F.Fab")
		)
		(fp_line
			(start 0.67945 -0.3048)
			(end 0.67945 0.3048)
			(stroke
				(width 0.1)
				(type default)
			)
			(layer "F.Fab")
		)
		(fp_line
			(start 0.67945 0.3048)
			(end 0.120396 0.3048)
			(stroke
				(width 0.1)
				(type default)
			)
			(layer "F.Fab")
		)
		(pad "1" smd circle
			(at -0.40005 0)
			(size 0 0)
			(layers "F.Cu" "F.Mask" "F.Paste")
			(net "P3V3_AUX")
		)
		(pad "2" smd circle
			(at 0.40005 0)
			(size 0 0)
			(layers "F.Cu" "F.Mask" "F.Paste")
			(net "P3V3_OCP_FAULT_2")
		)
	)
	(footprint ""
		(layer "F.Cu")
		(at 435.102 -165.9509 90)
		(property "Reference" "R1332"
			(at 0 0 90)
			(layer "F.SilkS")
			(hide yes)
			(effects
				(font
					(size 1.27 1.27)
				)
			)
		)
		(property "Value" ""
			(at 0 0 90)
			(layer "F.Fab")
			(effects
				(font
					(size 1.27 1.27)
				)
			)
		)
		(duplicate_pad_numbers_are_jumpers no)
		(fp_line
			(start 0.7874 -0.4064)
			(end 0.7874 0.4064)
			(stroke
				(width 0.1524)
				(type default)
			)
			(layer "F.SilkS")
		)
		(fp_line
			(start -0.7874 -0.4064)
			(end 0.7874 -0.4064)
			(stroke
				(width 0.1524)
				(type default)
			)
			(layer "F.SilkS")
		)
		(fp_line
			(start 0.7874 0.4064)
			(end -0.7874 0.4064)
			(stroke
				(width 0.1524)
				(type default)
			)
			(layer "F.SilkS")
		)
		(fp_line
			(start -0.7874 0.4064)
			(end -0.7874 -0.4064)
			(stroke
				(width 0.1524)
				(type default)
			)
			(layer "F.SilkS")
		)
		(fp_line
			(start -0.12065 -0.305054)
			(end -0.12065 -0.2794)
			(stroke
				(width 0.1)
				(type default)
			)
			(layer "F.Fab")
		)
		(fp_line
			(start -0.67945 -0.305054)
			(end -0.12065 -0.305054)
			(stroke
				(width 0.1)
				(type default)
			)
			(layer "F.Fab")
		)
		(fp_line
			(start 0.67945 -0.3048)
			(end 0.67945 0.3048)
			(stroke
				(width 0.1)
				(type default)
			)
			(layer "F.Fab")
		)
		(fp_line
			(start 0.12065 -0.3048)
			(end 0.67945 -0.3048)
			(stroke
				(width 0.1)
				(type default)
			)
			(layer "F.Fab")
		)
		(fp_line
			(start 0.12065 -0.2794)
			(end 0.12065 -0.3048)
			(stroke
				(width 0.1)
				(type default)
			)
			(layer "F.Fab")
		)
		(fp_line
			(start -0.12065 -0.2794)
			(end 0.12065 -0.2794)
			(stroke
				(width 0.1)
				(type default)
			)
			(layer "F.Fab")
		)
		(fp_line
			(start 0.120396 0.2794)
			(end -0.12065 0.2794)
			(stroke
				(width 0.1)
				(type default)
			)
			(layer "F.Fab")
		)
		(fp_line
			(start -0.12065 0.2794)
			(end -0.12065 0.3048)
			(stroke
				(width 0.1)
				(type default)
			)
			(layer "F.Fab")
		)
		(fp_line
			(start 0.67945 0.3048)
			(end 0.120396 0.3048)
			(stroke
				(width 0.1)
				(type default)
			)
			(layer "F.Fab")
		)
		(fp_line
			(start 0.120396 0.3048)
			(end 0.120396 0.2794)
			(stroke
				(width 0.1)
				(type default)
			)
			(layer "F.Fab")
		)
		(fp_line
			(start -0.12065 0.3048)
			(end -0.67945 0.3048)
			(stroke
				(width 0.1)
				(type default)
			)
			(layer "F.Fab")
		)
		(fp_line
			(start -0.67945 0.3048)
			(end -0.67945 -0.305054)
			(stroke
				(width 0.1)
				(type default)
			)
			(layer "F.Fab")
		)
		(pad "1" smd rect
			(at -0.40005 0 270)
			(size 0.4572 0.508)
			(layers "F.Cu" "F.Mask" "F.Paste")
			(net "I3C_SPD_DDRGL_CPU0_BYPASS_SCL")
		)
		(pad "2" smd rect
			(at 0.40005 0 270)
			(size 0.4572 0.508)
			(layers "F.Cu" "F.Mask" "F.Paste")
			(net "I3C_SPD_DDRGL_CPU0_SCL")
		)
	)
	(footprint ""
		(layer "F.Cu")
		(at 12.896342 -194.36715 -90)
		(property "Reference" "R1837"
			(at -4.2799 1.094232 90)
			(unlocked yes)
			(layer "F.SilkS")
			(effects
				(font
					(size 0.7874 0.5842)
					(thickness 0.1524)
				)
				(justify left)
			)
		)
		(property "Value" ""
			(at 0 0 270)
			(layer "F.Fab")
			(effects
				(font
					(size 1.27 1.27)
				)
			)
		)
		(duplicate_pad_numbers_are_jumpers no)
		(fp_line
			(start -4.0386 1.7526)
			(end -4.0386 -1.7526)
			(stroke
				(width 0.1524)
				(type default)
			)
			(layer "F.SilkS")
		)
		(fp_line
			(start 4.0386 1.7526)
			(end -4.0386 1.7526)
			(stroke
				(width 0.1524)
				(type default)
			)
			(layer "F.SilkS")
		)
		(fp_line
			(start -4.0386 -1.7526)
			(end 4.0386 -1.7526)
			(stroke
				(width 0.1524)
				(type default)
			)
			(layer "F.SilkS")
		)
		(fp_line
			(start 4.0386 -1.7526)
			(end 4.0386 1.7526)
			(stroke
				(width 0.1524)
				(type default)
			)
			(layer "F.SilkS")
		)
		(fp_line
			(start -4.0386 1.7526)
			(end -4.0386 -1.7526)
			(stroke
				(width 0.1)
				(type default)
			)
			(layer "F.Fab")
		)
		(fp_line
			(start 4.0386 1.7526)
			(end -4.0386 1.7526)
			(stroke
				(width 0.1)
				(type default)
			)
			(layer "F.Fab")
		)
		(fp_line
			(start -4.0386 -1.7526)
			(end 4.0386 -1.7526)
			(stroke
				(width 0.1)
				(type default)
			)
			(layer "F.Fab")
		)
		(fp_line
			(start 4.0386 -1.7526)
			(end 4.0386 1.7526)
			(stroke
				(width 0.1)
				(type default)
			)
			(layer "F.Fab")
		)
		(pad "1" smd circle
			(at -3.700018 0 180)
			(size 0 0)
			(layers "F.Cu" "F.Mask" "F.Paste")
			(net "P12V_AUX")
		)
		(pad "2" smd circle
			(at 3.700018 0)
			(size 0 0)
			(layers "F.Cu" "F.Mask" "F.Paste")
			(net "P12V_MEM_CPU1")
		)
		(pad "3" smd rect
			(at -2.70002 0)
			(size 0.4064 1.1176)
			(layers "F.Cu" "F.Mask" "F.Paste")
			(net "TP_P12V_AUX_CPU1_DIMM_ISEN_P")
		)
		(pad "4" smd rect
			(at 2.70002 0)
			(size 0.4064 1.1176)
			(layers "F.Cu" "F.Mask" "F.Paste")
			(net "TP_P12V_AUX_CPU1_DIMM_ISEN_N")
		)
	)
	(footprint ""
		(layer "F.Cu")
		(at 380.899924 -22.29993)
		(property "Reference" "H87"
			(at -5.041392 -5.687568 0)
			(unlocked yes)
			(layer "F.SilkS")
			(effects
				(font
					(size 0.7874 0.5842)
					(thickness 0.1524)
				)
				(justify left)
			)
		)
		(property "Value" ""
			(at 0 0 0)
			(layer "F.Fab")
			(effects
				(font
					(size 1.27 1.27)
				)
			)
		)
		(duplicate_pad_numbers_are_jumpers no)
		(pad "1" thru_hole circle
			(at 0 0)
			(size 10.0076 10.0076)
			(drill 5.6134)
			(layers "*.Cu" "*.Mask")
			(remove_unused_layers no)
			(net "GND")
			(clearance -1.9431)
		)
	)
	(footprint ""
		(layer "F.Cu")
		(at 429.4632 -16.100298 90)
		(property "Reference" "C1576"
			(at 0 0 90)
			(layer "F.SilkS")
			(hide yes)
			(effects
				(font
					(size 1.27 1.27)
				)
			)
		)
		(property "Value" ""
			(at 0 0 90)
			(layer "F.Fab")
			(effects
				(font
					(size 1.27 1.27)
				)
			)
		)
		(duplicate_pad_numbers_are_jumpers no)
		(fp_line
			(start 0.299974 -0.150114)
			(end 0.299974 0.150114)
			(stroke
				(width 0.1)
				(type default)
			)
			(layer "F.Fab")
		)
		(fp_line
			(start -0.299974 -0.150114)
			(end 0.299974 -0.150114)
			(stroke
				(width 0.1)
				(type default)
			)
			(layer "F.Fab")
		)
		(fp_line
			(start 0.299974 0.150114)
			(end -0.299974 0.150114)
			(stroke
				(width 0.1)
				(type default)
			)
			(layer "F.Fab")
		)
		(fp_line
			(start -0.299974 0.150114)
			(end -0.299974 -0.150114)
			(stroke
				(width 0.1)
				(type default)
			)
			(layer "F.Fab")
		)
		(pad "1" smd rect
			(at -0.2667 0 90)
			(size 0.3048 0.381)
			(layers "F.Cu" "F.Mask" "F.Paste")
			(net "P5E_CPU0_G3_TX_C_DN<1>")
		)
		(pad "2" smd rect
			(at 0.2667 0 90)
			(size 0.3048 0.381)
			(layers "F.Cu" "F.Mask" "F.Paste")
			(net "P5E_CPU0_G3_TX_DN<1>")
		)
	)
	(footprint ""
		(layer "F.Cu")
		(at 110.63732 -325.116444 180)
		(property "Reference" "TP16"
			(at -0.91948 -0.099314 0)
			(unlocked yes)
			(layer "F.SilkS")
			(effects
				(font
					(size 0.7874 0.5842)
					(thickness 0.1524)
				)
				(justify left)
			)
		)
		(property "Value" ""
			(at 0 0 180)
			(layer "F.Fab")
			(effects
				(font
					(size 1.27 1.27)
				)
			)
		)
		(duplicate_pad_numbers_are_jumpers no)
		(pad "1" smd circle
			(at 0 0 180)
			(size 0.762 0.762)
			(layers "F.Cu" "F.Mask" "F.Paste")
			(net "VSENSE_PVDDCR_CPU1_P1_DP")
		)
	)
	(footprint ""
		(layer "F.Cu")
		(at 40.51554 -346.813632 -90)
		(property "Reference" "PC624_3"
			(at 0 0 270)
			(layer "F.SilkS")
			(hide yes)
			(effects
				(font
					(size 1.27 1.27)
				)
			)
		)
		(property "Value" ""
			(at 0 0 270)
			(layer "F.Fab")
			(effects
				(font
					(size 1.27 1.27)
				)
			)
		)
		(duplicate_pad_numbers_are_jumpers no)
		(fp_line
			(start -0.7874 0.4064)
			(end -0.7874 -0.4064)
			(stroke
				(width 0.1524)
				(type default)
			)
			(layer "F.SilkS")
		)
		(fp_line
			(start 0.7874 0.4064)
			(end -0.7874 0.4064)
			(stroke
				(width 0.1524)
				(type default)
			)
			(layer "F.SilkS")
		)
		(fp_line
			(start -0.7874 -0.4064)
			(end 0.7874 -0.4064)
			(stroke
				(width 0.1524)
				(type default)
			)
			(layer "F.SilkS")
		)
		(fp_line
			(start 0.7874 -0.4064)
			(end 0.7874 0.4064)
			(stroke
				(width 0.1524)
				(type default)
			)
			(layer "F.SilkS")
		)
		(fp_line
			(start -0.67945 0.3048)
			(end -0.67945 -0.305054)
			(stroke
				(width 0.1)
				(type default)
			)
			(layer "F.Fab")
		)
		(fp_line
			(start -0.12065 0.3048)
			(end -0.67945 0.3048)
			(stroke
				(width 0.1)
				(type default)
			)
			(layer "F.Fab")
		)
		(fp_line
			(start 0.120396 0.3048)
			(end 0.120396 0.2794)
			(stroke
				(width 0.1)
				(type default)
			)
			(layer "F.Fab")
		)
		(fp_line
			(start 0.67945 0.3048)
			(end 0.120396 0.3048)
			(stroke
				(width 0.1)
				(type default)
			)
			(layer "F.Fab")
		)
		(fp_line
			(start -0.12065 0.2794)
			(end -0.12065 0.3048)
			(stroke
				(width 0.1)
				(type default)
			)
			(layer "F.Fab")
		)
		(fp_line
			(start 0.120396 0.2794)
			(end -0.12065 0.2794)
			(stroke
				(width 0.1)
				(type default)
			)
			(layer "F.Fab")
		)
		(fp_line
			(start -0.12065 -0.2794)
			(end 0.12065 -0.2794)
			(stroke
				(width 0.1)
				(type default)
			)
			(layer "F.Fab")
		)
		(fp_line
			(start 0.12065 -0.2794)
			(end 0.12065 -0.3048)
			(stroke
				(width 0.1)
				(type default)
			)
			(layer "F.Fab")
		)
		(fp_line
			(start 0.12065 -0.3048)
			(end 0.67945 -0.3048)
			(stroke
				(width 0.1)
				(type default)
			)
			(layer "F.Fab")
		)
		(fp_line
			(start 0.67945 -0.3048)
			(end 0.67945 0.3048)
			(stroke
				(width 0.1)
				(type default)
			)
			(layer "F.Fab")
		)
		(fp_line
			(start -0.67945 -0.305054)
			(end -0.12065 -0.305054)
			(stroke
				(width 0.1)
				(type default)
			)
			(layer "F.Fab")
		)
		(fp_line
			(start -0.12065 -0.305054)
			(end -0.12065 -0.2794)
			(stroke
				(width 0.1)
				(type default)
			)
			(layer "F.Fab")
		)
		(pad "1" smd circle
			(at -0.40005 0 270)
			(size 0 0)
			(layers "F.Cu" "F.Mask" "F.Paste")
			(net "SW_P12V_AUX_PVDDIO_P1_FLT")
		)
		(pad "2" smd circle
			(at 0.40005 0 270)
			(size 0 0)
			(layers "F.Cu" "F.Mask" "F.Paste")
			(net "GND")
		)
	)
	(footprint ""
		(layer "F.Cu")
		(at 49.784 -39.751)
		(property "Reference" "R1165"
			(at 0 0 0)
			(layer "F.SilkS")
			(hide yes)
			(effects
				(font
					(size 1.27 1.27)
				)
			)
		)
		(property "Value" ""
			(at 0 0 0)
			(layer "F.Fab")
			(effects
				(font
					(size 1.27 1.27)
				)
			)
		)
		(duplicate_pad_numbers_are_jumpers no)
		(fp_line
			(start -0.7874 -0.4064)
			(end 0.7874 -0.4064)
			(stroke
				(width 0.1524)
				(type default)
			)
			(layer "F.SilkS")
		)
		(fp_line
			(start -0.7874 0.4064)
			(end -0.7874 -0.4064)
			(stroke
				(width 0.1524)
				(type default)
			)
			(layer "F.SilkS")
		)
		(fp_line
			(start 0.7874 -0.4064)
			(end 0.7874 0.4064)
			(stroke
				(width 0.1524)
				(type default)
			)
			(layer "F.SilkS")
		)
		(fp_line
			(start 0.7874 0.4064)
			(end -0.7874 0.4064)
			(stroke
				(width 0.1524)
				(type default)
			)
			(layer "F.SilkS")
		)
		(fp_line
			(start -0.67945 -0.305054)
			(end -0.12065 -0.305054)
			(stroke
				(width 0.1)
				(type default)
			)
			(layer "F.Fab")
		)
		(fp_line
			(start -0.67945 0.3048)
			(end -0.67945 -0.305054)
			(stroke
				(width 0.1)
				(type default)
			)
			(layer "F.Fab")
		)
		(fp_line
			(start -0.12065 -0.305054)
			(end -0.12065 -0.2794)
			(stroke
				(width 0.1)
				(type default)
			)
			(layer "F.Fab")
		)
		(fp_line
			(start -0.12065 -0.2794)
			(end 0.12065 -0.2794)
			(stroke
				(width 0.1)
				(type default)
			)
			(layer "F.Fab")
		)
		(fp_line
			(start -0.12065 0.2794)
			(end -0.12065 0.3048)
			(stroke
				(width 0.1)
				(type default)
			)
			(layer "F.Fab")
		)
		(fp_line
			(start -0.12065 0.3048)
			(end -0.67945 0.3048)
			(stroke
				(width 0.1)
				(type default)
			)
			(layer "F.Fab")
		)
		(fp_line
			(start 0.120396 0.2794)
			(end -0.12065 0.2794)
			(stroke
				(width 0.1)
				(type default)
			)
			(layer "F.Fab")
		)
		(fp_line
			(start 0.120396 0.3048)
			(end 0.120396 0.2794)
			(stroke
				(width 0.1)
				(type default)
			)
			(layer "F.Fab")
		)
		(fp_line
			(start 0.12065 -0.3048)
			(end 0.67945 -0.3048)
			(stroke
				(width 0.1)
				(type default)
			)
			(layer "F.Fab")
		)
		(fp_line
			(start 0.12065 -0.2794)
			(end 0.12065 -0.3048)
			(stroke
				(width 0.1)
				(type default)
			)
			(layer "F.Fab")
		)
		(fp_line
			(start 0.67945 -0.3048)
			(end 0.67945 0.3048)
			(stroke
				(width 0.1)
				(type default)
			)
			(layer "F.Fab")
		)
		(fp_line
			(start 0.67945 0.3048)
			(end 0.120396 0.3048)
			(stroke
				(width 0.1)
				(type default)
			)
			(layer "F.Fab")
		)
		(pad "1" smd circle
			(at -0.40005 0)
			(size 0 0)
			(layers "F.Cu" "F.Mask" "F.Paste")
			(net "P3V3_AUX")
		)
		(pad "2" smd circle
			(at 0.40005 0)
			(size 0 0)
			(layers "F.Cu" "F.Mask" "F.Paste")
			(net "P12V_OCP_V3_2_EN_R3")
		)
	)
)
